# T6G (Grand Teton) — schematic parts with pin connectivity, parts 4573–4586 of 8303; source: Cadence DE-HDL packaged netlist (pstxprt.dat, pstxnet.dat, pstchip.dat)

PU14  ISL99390FRZTR5935  ISL99390FRZ-TR5935 IC  pkg QFN21_6X5XB  page 202
  1  VOS  IN  = PVDDCR_CPU1_P0_VOS4
  2  AGND  POWER  = GND
  3  VCC  POWER  = PVDDCR_CPU1_P0_VCC4
  4  PVCC  POWER  = PVDDCR_CPU1_P0_PVCC
  5  PGND1  POWER  = GND
  6  GL1  OUT  = NC_PVDDCR_CPU1_P0_GL1_4
  7_9-20_24  PGND2  POWER  = GND
  10_19  SW  OUT  = SW_PVDDCR_CPU1_P0_SW4
  25_29  VIN1  IN  = SW_P12V_AUX_PVDDCR_CPU1_P0_FLT
  30  VIN2  IN  = SW_P12V_AUX_PVDDCR_CPU1_P0_FLT
  31  DNC  TRI  = NC_PVDDCR_CPU1_P0_DNC4
  32  PHASE  POWER  = SW_PVDDCR_CPU1_P0_BOOTR4
  33  BOOT  POWER  = SW_PVDDCR_CPU1_P0_BOOT4
  34  PWM  IN  = PVDDCR_CPU1_P0_PWM4
  35  EN  IN  = PVDDCR_CPU1_P0_VCC4
  36  TOUT_FLT  OUT  = PVDDCR_CPU1_P0_TEMP0
  37  LSET  OUT  = PVDDCR_CPU1_P0_LSET4
  38  IOUT  OUT  = PVDDCR_CPU1_P0_IMON4
  39  REFIN  IN  = PVDDCR_CPU1_P0_VCCS
  40  PGND3  POWER  = GND
  41  GL2  OUT  = NC_PVDDCR_CPU1_P0_GL2_4

PU15  ISL99390FRZTR5935  ISL99390FRZ-TR5935 IC  pkg QFN21_6X5XB  page 202
  1  VOS  IN  = PVDDCR_CPU1_P0_VOS3
  2  AGND  POWER  = GND
  3  VCC  POWER  = PVDDCR_CPU1_P0_VCC3
  4  PVCC  POWER  = PVDDCR_CPU1_P0_PVCC
  5  PGND1  POWER  = GND
  6  GL1  OUT  = NC_PVDDCR_CPU1_P0_GL1_3
  7_9-20_24  PGND2  POWER  = GND
  10_19  SW  OUT  = SW_PVDDCR_CPU1_P0_SW3
  25_29  VIN1  IN  = SW_P12V_AUX_PVDDCR_CPU1_P0_FLT
  30  VIN2  IN  = SW_P12V_AUX_PVDDCR_CPU1_P0_FLT
  31  DNC  TRI  = NC_PVDDCR_CPU1_P0_DNC3
  32  PHASE  POWER  = SW_PVDDCR_CPU1_P0_BOOTR3
  33  BOOT  POWER  = SW_PVDDCR_CPU1_P0_BOOT3
  34  PWM  IN  = PVDDCR_CPU1_P0_PWM3
  35  EN  IN  = PVDDCR_CPU1_P0_VCC3
  36  TOUT_FLT  OUT  = PVDDCR_CPU1_P0_TEMP0
  37  LSET  OUT  = PVDDCR_CPU1_P0_LSET3
  38  IOUT  OUT  = PVDDCR_CPU1_P0_IMON3
  39  REFIN  IN  = PVDDCR_CPU1_P0_VCCS
  40  PGND3  POWER  = GND
  41  GL2  OUT  = NC_PVDDCR_CPU1_P0_GL2_3

PU16  ISL99390FRZTR5935  ISL99390FRZ-TR5935 IC  pkg QFN21_6X5XB  page 203
  1  VOS  IN  = PVDDCR_CPU1_P0_VOS5
  2  AGND  POWER  = GND
  3  VCC  POWER  = PVDDCR_CPU1_P0_VCC5
  4  PVCC  POWER  = PVDDCR_CPU1_P0_PVCC
  5  PGND1  POWER  = GND
  6  GL1  OUT  = NC_PVDDCR_CPU1_P0_GL1_5
  7_9-20_24  PGND2  POWER  = GND
  10_19  SW  OUT  = SW_PVDDCR_CPU1_P0_SW5
  25_29  VIN1  IN  = SW_P12V_AUX_PVDDCR_CPU1_P0_FLT
  30  VIN2  IN  = SW_P12V_AUX_PVDDCR_CPU1_P0_FLT
  31  DNC  TRI  = NC_PVDDCR_CPU1_P0_DNC5
  32  PHASE  POWER  = SW_PVDDCR_CPU1_P0_BOOTR5
  33  BOOT  POWER  = SW_PVDDCR_CPU1_P0_BOOT5
  34  PWM  IN  = PVDDCR_CPU1_P0_PWM5
  35  EN  IN  = PVDDCR_CPU1_P0_VCC5
  36  TOUT_FLT  OUT  = PVDDCR_CPU1_P0_TEMP0
  37  LSET  OUT  = PVDDCR_CPU1_P0_LSET5
  38  IOUT  OUT  = PVDDCR_CPU1_P0_IMON5
  39  REFIN  IN  = PVDDCR_CPU1_P0_VCCS
  40  PGND3  POWER  = GND
  41  GL2  OUT  = NC_PVDDCR_CPU1_P0_GL2_5

PU17  ISL99390FRZTR5935  ISL99390FRZ-TR5935 IC  pkg QFN21_6X5XB  page 205
  1  VOS  IN  = PVDDIO_P0_VOS1
  2  AGND  POWER  = GND
  3  VCC  POWER  = PVDDIO_P0_VCC1
  4  PVCC  POWER  = PVDDCR_CPU1_P0_PVCC
  5  PGND1  POWER  = GND
  6  GL1  OUT  = NC_PVDDIO_P0_GL1_1
  7_9-20_24  PGND2  POWER  = GND
  10_19  SW  OUT  = SW_PVDDIO_P0_SW1
  25_29  VIN1  IN  = SW_P12V_AUX_PVDDIO_P0_FLT
  30  VIN2  IN  = SW_P12V_AUX_PVDDIO_P0_FLT
  31  DNC  TRI  = NC_PVDDIO_P0_DNC1
  32  PHASE  POWER  = SW_PVDDIO_P0_BOOTR1
  33  BOOT  POWER  = SW_PVDDIO_P0_BOOT1
  34  PWM  IN  = PVDDIO_P0_PWM1
  35  EN  IN  = PVDDIO_P0_VCC1
  36  TOUT_FLT  OUT  = PVDDIO_P0_TEMP1
  37  LSET  OUT  = PVDDIO_P0_LSET1
  38  IOUT  OUT  = PVDDIO_P0_IMON1
  39  REFIN  IN  = PVDDCR_CPU1_P0_VCCS
  40  PGND3  POWER  = GND
  41  GL2  OUT  = NC_PVDDIO_P0_GL2_1

PU18  ISL99390FRZTR5935  ISL99390FRZ-TR5935 IC  pkg QFN21_6X5XB  page 205
  1  VOS  IN  = PVDDIO_P0_VOS2
  2  AGND  POWER  = GND
  3  VCC  POWER  = PVDDIO_P0_VCC2
  4  PVCC  POWER  = PVDDCR_CPU1_P0_PVCC
  5  PGND1  POWER  = GND
  6  GL1  OUT  = NC_PVDDIO_P0_GL1_2
  7_9-20_24  PGND2  POWER  = GND
  10_19  SW  OUT  = SW_PVDDIO_P0_SW2
  25_29  VIN1  IN  = SW_P12V_AUX_PVDDIO_P0_FLT
  30  VIN2  IN  = SW_P12V_AUX_PVDDIO_P0_FLT
  31  DNC  TRI  = NC_PVDDIO_P0_DNC2
  32  PHASE  POWER  = SW_PVDDIO_P0_BOOTR2
  33  BOOT  POWER  = SW_PVDDIO_P0_BOOT2
  34  PWM  IN  = PVDDIO_P0_PWM2
  35  EN  IN  = PVDDIO_P0_VCC2
  36  TOUT_FLT  OUT  = PVDDIO_P0_TEMP1
  37  LSET  OUT  = PVDDIO_P0_LSET2
  38  IOUT  OUT  = PVDDIO_P0_IMON2
  39  REFIN  IN  = PVDDCR_CPU1_P0_VCCS
  40  PGND3  POWER  = GND
  41  GL2  OUT  = NC_PVDDIO_P0_GL2_2

PU19  ISL99390FRZTR5935  ISL99390FRZ-TR5935 IC  pkg QFN21_6X5XB  page 206
  1  VOS  IN  = PVDDIO_P0_VOS3
  2  AGND  POWER  = GND
  3  VCC  POWER  = PVDDIO_P0_VCC3
  4  PVCC  POWER  = PVDDCR_CPU1_P0_PVCC
  5  PGND1  POWER  = GND
  6  GL1  OUT  = NC_PVDDIO_P0_GL1_3
  7_9-20_24  PGND2  POWER  = GND
  10_19  SW  OUT  = SW_PVDDIO_P0_SW3
  25_29  VIN1  IN  = SW_P12V_AUX_PVDDIO_P0_FLT
  30  VIN2  IN  = SW_P12V_AUX_PVDDIO_P0_FLT
  31  DNC  TRI  = NC_PVDDIO_P0_DNC3
  32  PHASE  POWER  = SW_PVDDIO_P0_BOOTR3
  33  BOOT  POWER  = SW_PVDDIO_P0_BOOT3
  34  PWM  IN  = PVDDIO_P0_PWM3
  35  EN  IN  = PVDDIO_P0_VCC3
  36  TOUT_FLT  OUT  = PVDDIO_P0_TEMP1
  37  LSET  OUT  = PVDDIO_P0_LSET3
  38  IOUT  OUT  = PVDDIO_P0_IMON3
  39  REFIN  IN  = PVDDCR_CPU1_P0_VCCS
  40  PGND3  POWER  = GND
  41  GL2  OUT  = NC_PVDDIO_P0_GL2_3

PU20  ISL99390FRZTR5935  ISL99390FRZ-TR5935 IC  pkg QFN21_6X5XB  page 206
  1  VOS  IN  = PVDDIO_P0_VOS4
  2  AGND  POWER  = GND
  3  VCC  POWER  = PVDDIO_P0_VCC4
  4  PVCC  POWER  = PVDDCR_CPU1_P0_PVCC
  5  PGND1  POWER  = GND
  6  GL1  OUT  = NC_PVDDIO_P0_GL1_4
  7_9-20_24  PGND2  POWER  = GND
  10_19  SW  OUT  = SW_PVDDIO_P0_SW4
  25_29  VIN1  IN  = SW_P12V_AUX_PVDDIO_P0_FLT
  30  VIN2  IN  = SW_P12V_AUX_PVDDIO_P0_FLT
  31  DNC  TRI  = NC_PVDDIO_P0_DNC4
  32  PHASE  POWER  = SW_PVDDIO_P0_BOOTR4
  33  BOOT  POWER  = SW_PVDDIO_P0_BOOT4
  34  PWM  IN  = PVDDIO_P0_PWM4
  35  EN  IN  = PVDDIO_P0_VCC4
  36  TOUT_FLT  OUT  = PVDDIO_P0_TEMP1
  37  LSET  OUT  = PVDDIO_P0_LSET4
  38  IOUT  OUT  = PVDDIO_P0_IMON4
  39  REFIN  IN  = PVDDCR_CPU1_P0_VCCS
  40  PGND3  POWER  = GND
  41  GL2  OUT  = NC_PVDDIO_P0_GL2_4

PU21  RAA229621GNPHA0  RAA229621GNP#HA0 IC  pkg QFN40_TH_0-4_5X5XE  page 207
  1  PWM0  OUT  = NC_PVDD11_S3_P0_PWM8
  2  PWM1  OUT  = NC_PVDD11_S3_P0_PWM7
  3  PWM2  OUT  = NC_PVDD11_S3_P0_PWM6
  4  PWM3  OUT  = NC_PVDD11_S3_P0_PWM5
  5  PWM4  OUT  = NC_PVDD11_S3_P0_PWM4
  6  PWM5  OUT  = NC_PVDD11_S3_P0_PWM3
  7  PWM6  OUT  = PVDD11_S3_P0_PWM2
  8  PWM7  OUT  = PVDD11_S3_P0_PWM1
  9  PMSDA  BI  = PVDD11_S3_P0_PMSDA_R
  10  PMSCL  IN  = PVDD11_S3_P0_PMSCL_R
  11  NPMALERT  OUT  = PVDD11_S3_P0_PMALERT_R
  12  PG0  OUT  = PWRGD_PVDD11_S3_P0_R
  13  EN0  IN  = PVDD11_S3_P0_EN_R
  14  RESET_L  IN  = PVDD11_S3_P0_RESET_N_R
  15  VDDIO  IN  = PVDD11_S3_P0_VDDIO
  16  PG1  OUT  = NC_PVDD11_S3_P0_PG1
  17  SVD  BI  = GND
  18  SVC  IN  = GND
  19  SVTO  OUT  = NC_PVDD11_S3_P0_SVTO
  20  SVTI  IN  = GND
  21  VSEN0  IN  = VSENSE_PVDD11_S3_P0_R
  22  RGND0  IN  = VSENSE_VSS_SENSE_C_P0
  23  CS7  IN  = PVDD11_S3_P0_IMON1
  24  CS6  IN  = PVDD11_S3_P0_IMON2
  25  CS5  IN  = NC_PVDD11_S3_P0_IMON3
  26  CS4  IN  = NC_PVDD11_S3_P0_IMON4
  27  CS3  IN  = NC_PVDD11_S3_P0_IMON5
  28  CS2  IN  = NC_PVDD11_S3_P0_IMON6
  29  CS1  IN  = NC_PVDD11_S3_P0_IMON7
  30  CS0  IN  = NC_PVDD11_S3_P0_IMON8
  31  RGND1  IN  = GND
  32  VSEN1  IN  = GND
  33  OCP_L  OUT  = PVDD11_S3_P0_OCP_N_R
  34  \en1||addr_cfg\  IN  = PVDD11_S3_P0_ADDR_CFG
  35  TEMP1  IN  = PVDD11_S3_P0_TEMP1
  36  TEMP0  IN  = PVDD11_S3_P0_TEMP0
  37  \vmon||iinsen\  IN  = PVDD11_S3_P0_VMON
  38  VINSEN  IN  = PVDD11_S3_P0_VINSEN
  39  VCC  POWER  = PVDD11_S3_P0_VCC
  40  VCCS  POWER  = PVDD11_S3_P0_VCCS
  TH  TH_GND  POWER  = GND

PU22  ISL99390FRZTR5935  ISL99390FRZ-TR5935 IC  pkg QFN21_6X5XB  page 208
  1  VOS  IN  = PVDD11_S3_P0_VOS1
  2  AGND  POWER  = GND
  3  VCC  POWER  = PVDD11_S3_P0_VCC1
  4  PVCC  POWER  = PVDD11_S3_P0_PVCC
  5  PGND1  POWER  = GND
  6  GL1  OUT  = NC_PVDD11_S3_P0_GL1_1
  7_9-20_24  PGND2  POWER  = GND
  10_19  SW  OUT  = SW_PVDD11_S3_P0_SW1
  25_29  VIN1  IN  = SW_P12V_AUX_PVDD11_S3_P0_FLT
  30  VIN2  IN  = SW_P12V_AUX_PVDD11_S3_P0_FLT
  31  DNC  TRI  = NC_PVDD11_S3_P0_DNC1
  32  PHASE  POWER  = SW_PVDD11_S3_P0_PH1
  33  BOOT  POWER  = SW_PVDD11_S3_P0_BOOT1
  34  PWM  IN  = PVDD11_S3_P0_PWM1
  35  EN  IN  = PVDD11_S3_P0_VCC1
  36  TOUT_FLT  OUT  = PVDD11_S3_P0_TEMP0
  37  LSET  OUT  = PVDD11_S3_P0_LSET1
  38  IOUT  OUT  = PVDD11_S3_P0_IMON1
  39  REFIN  IN  = PVDD11_S3_P0_VCCS
  40  PGND3  POWER  = GND
  41  GL2  OUT  = NC_PVDD11_S3_P0_GL2_1

PU23  ISL99390FRZTR5935  ISL99390FRZ-TR5935 IC  pkg QFN21_6X5XB  page 208
  1  VOS  IN  = PVDD11_S3_P0_VOS2
  2  AGND  POWER  = GND
  3  VCC  POWER  = PVDD11_S3_P0_VCC2
  4  PVCC  POWER  = PVDD11_S3_P0_PVCC
  5  PGND1  POWER  = GND
  6  GL1  OUT  = NC_PVDD11_S3_P0_GL1_2
  7_9-20_24  PGND2  POWER  = GND
  10_19  SW  OUT  = SW_PVDD11_S3_P0_SW2
  25_29  VIN1  IN  = SW_P12V_AUX_PVDD11_S3_P0_FLT
  30  VIN2  IN  = SW_P12V_AUX_PVDD11_S3_P0_FLT
  31  DNC  TRI  = NC_PVDD11_S3_P0_DNC2
  32  PHASE  POWER  = SW_PVDD11_S3_P0_PH2
  33  BOOT  POWER  = SW_PVDD11_S3_P0_BOOT2
  34  PWM  IN  = PVDD11_S3_P0_PWM2
  35  EN  IN  = PVDD11_S3_P0_VCC2
  36  TOUT_FLT  OUT  = PVDD11_S3_P0_TEMP0
  37  LSET  OUT  = PVDD11_S3_P0_LSET2
  38  IOUT  OUT  = PVDD11_S3_P0_IMON2
  39  REFIN  IN  = PVDD11_S3_P0_VCCS
  40  PGND3  POWER  = GND
  41  GL2  OUT  = NC_PVDD11_S3_P0_GL2_2

PU24  ISL99390FRZTR5935  ISL99390FRZ-TR5935 IC  pkg QFN21_6X5XB  page 213
  1  VOS  IN  = PVDDCR_CPU0_P1_VOS6
  2  AGND  POWER  = GND
  3  VCC  POWER  = PVDDCR_CPU0_P1_VCC6
  4  PVCC  POWER  = PVDDCR_CPU0_P1_PVCC
  5  PGND1  POWER  = GND
  6  GL1  OUT  = NC_PVDDCR_CPU0_P1_GL1_6
  7_9-20_24  PGND2  POWER  = GND
  10_19  SW  OUT  = SW_PVDDCR_CPU0_P1_SW6
  25_29  VIN1  IN  = SW_P12V_AUX_PVDDCR_CPU0_P1_FLT
  30  VIN2  IN  = SW_P12V_AUX_PVDDCR_CPU0_P1_FLT
  31  DNC  TRI  = NC_PVDDCR_CPU0_P1_DNC6
  32  PHASE  POWER  = SW_PVDDCR_CPU0_P1_PH6
  33  BOOT  POWER  = SW_PVDDCR_CPU0_P1_BOOT6
  34  PWM  IN  = PVDDCR_CPU0_P1_PWM6
  35  EN  IN  = PVDDCR_CPU0_P1_VCC6
  36  TOUT_FLT  OUT  = PVDDCR_CPU0_P1_TEMP0
  37  LSET  OUT  = PVDDCR_CPU0_P1_LSET6
  38  IOUT  OUT  = PVDDCR_CPU0_P1_IMON6
  39  REFIN  IN  = PVDDCR_CPU0_P1_VCCS
  40  PGND3  POWER  = GND
  41  GL2  OUT  = NC_PVDDCR_CPU0_P1_GL2_6

PU25  RAA229620GNPHA0  RAA229620GNP#HA0 IC  pkg QFN48_TH_0-4_6X6XH  page 210
  1  PWM0  OUT  = PVDDCR_SOC_P1_PWM1
  2  PWM1  OUT  = PVDDCR_SOC_P1_PWM2
  3  PWM2  OUT  = PVDDCR_SOC_P1_PWM3
  4  PWM3  OUT  = NC_PVDDCR_CPU0_P1_PWM9
  5  PWM4  OUT  = NC_PVDDCR_CPU0_P1_PWM8
  6  PWM5  OUT  = NC_PVDDCR_CPU0_P1_PWM7
  7  PWM6  OUT  = PVDDCR_CPU0_P1_PWM6
  8  PWM7  OUT  = PVDDCR_CPU0_P1_PWM5
  9  PWM8  OUT  = PVDDCR_CPU0_P1_PWM4
  10  PWM9  OUT  = PVDDCR_CPU0_P1_PWM3
  11  PWM10  OUT  = PVDDCR_CPU0_P1_PWM2
  12  PWM11  OUT  = PVDDCR_CPU0_P1_PWM1
  13  PMSDA  BI  = PVDDCR_CPU0_P1_PMSDA_R
  14  PMSCL  IN  = PVDDCR_CPU0_P1_PMSCL_R
  15  NPMALERT  OUT  = PVDDCR_CPU0_P1_PMALERT_R
  16  PG0  OUT  = PWRGD_PVDDCR_CPU0_P1_R
  17  EN0  IN  = PVDDCR_CPU0_P1_EN_R
  18  RESET_L  IN  = PVDDCR_CPU0_P1_RESET_N_R
  19  VDDIO  POWER  = PVDD18_S5_P1
  20  PG1  OUT  = PWRGD_PVDDCR_SOC_P1_R
  21  SVD  IN  = SVID_PVDDCR_CPU0_P1_SVD_R1
  22  SVC  IN  = SVID_PVDDCR_CPU0_P1_SVC_R1
  23  SVTO  OUT  = SVID_PVDDCR_CPU0_P1_SVTO_R
  24  SVTI  IN  = SVID_PVDDCR_CPU0_P1_SVTI_R
  25  VSEN0  IN  = VSENSE_PVDDCR_CPU0_P1_VSEN0
  26  RGND0  IN  = VSENSE_VSS_SENSE_A_P1
  27  CS11  IN  = PVDDCR_CPU0_P1_IMON1
  28  CS10  IN  = PVDDCR_CPU0_P1_IMON2
  29  CS9  IN  = PVDDCR_CPU0_P1_IMON3
  30  CS8  IN  = PVDDCR_CPU0_P1_IMON4
  31  CS7  IN  = PVDDCR_CPU0_P1_IMON5
  32  CS6  IN  = PVDDCR_CPU0_P1_IMON6
  33  CS5  IN  = NC_PVDDCR_CPU0_P1_IMON7
  34  CS4  IN  = NC_PVDDCR_CPU0_P1_IMON8
  35  CS3  IN  = NC_PVDDCR_CPU0_P1_IMON9
  36  CS2  IN  = PVDDCR_SOC_P1_IMON3
  37  CS1  IN  = PVDDCR_SOC_P1_IMON2
  38  CS0  IN  = PVDDCR_SOC_P1_IMON1
  39  RGND1  IN  = VSENSE_VSS_SENSE_A_P1
  40  VSEN1  IN  = VSENSE_PVDDCR_SOC_P1_VSEN1
  41  OCP_L  OUT  = PVDDCR_CPU0_P1_OCP_N_R
  42  \en1||addr_cfg\  IN  = PVDDCR_SOC_P1_EN//ADDR_CFG
  43  TEMP1  IN  = PVDDCR_SOC_P1_TEMP1
  44  TEMP0  IN  = PVDDCR_CPU0_P1_TEMP0
  45  \vmon||iinsen\  BI  = PVDDCR_CPU0_P1_VMON
  46  VINSEN  IN  = PVDDCR_CPU0_P1_VINSEN
  47  VCC  POWER  = PVDDCR_CPU0_P1_VCC
  48  VCCS  POWER  = PVDDCR_CPU0_P1_VCCS
  TH  TH_GND  POWER  = GND

PU26  ISL99390FRZTR5935  ISL99390FRZ-TR5935 IC  pkg QFN21_6X5XB  page 211
  1  VOS  IN  = PVDDCR_CPU0_P1_VOS2
  2  AGND  POWER  = GND
  3  VCC  POWER  = PVDDCR_CPU0_P1_VCC2
  4  PVCC  POWER  = PVDDCR_CPU0_P1_PVCC
  5  PGND1  POWER  = GND
  6  GL1  OUT  = NC_PVDDCR_CPU0_P1_GL1_2
  7_9-20_24  PGND2  POWER  = GND
  10_19  SW  OUT  = SW_PVDDCR_CPU0_P1_SW2
  25_29  VIN1  IN  = SW_P12V_AUX_PVDDCR_CPU0_P1_FLT
  30  VIN2  IN  = SW_P12V_AUX_PVDDCR_CPU0_P1_FLT
  31  DNC  TRI  = NC_PVDDCR_CPU0_P1_DNC2
  32  PHASE  POWER  = SW_PVDDCR_CPU0_P1_PH2
  33  BOOT  POWER  = SW_PVDDCR_CPU0_P1_BOOT2
  34  PWM  IN  = PVDDCR_CPU0_P1_PWM2
  35  EN  IN  = PVDDCR_CPU0_P1_VCC2
  36  TOUT_FLT  OUT  = PVDDCR_CPU0_P1_TEMP0
  37  LSET  OUT  = PVDDCR_CPU0_P1_LSET2
  38  IOUT  OUT  = PVDDCR_CPU0_P1_IMON2
  39  REFIN  IN  = PVDDCR_CPU0_P1_VCCS
  40  PGND3  POWER  = GND
  41  GL2  OUT  = NC_PVDDCR_CPU0_P1_GL2_2

PU27  ISL99390FRZTR5935  ISL99390FRZ-TR5935 IC  pkg QFN21_6X5XB  page 212
  1  VOS  IN  = PVDDCR_CPU0_P1_VOS3
  2  AGND  POWER  = GND
  3  VCC  POWER  = PVDDCR_CPU0_P1_VCC3
  4  PVCC  POWER  = PVDDCR_CPU0_P1_PVCC
  5  PGND1  POWER  = GND
  6  GL1  OUT  = NC_PVDDCR_CPU0_P1_GL1_3
  7_9-20_24  PGND2  POWER  = GND
  10_19  SW  OUT  = SW_PVDDCR_CPU0_P1_SW3
  25_29  VIN1  IN  = SW_P12V_AUX_PVDDCR_CPU0_P1_FLT
  30  VIN2  IN  = SW_P12V_AUX_PVDDCR_CPU0_P1_FLT
  31  DNC  TRI  = NC_PVDDCR_CPU0_P1_DNC3
  32  PHASE  POWER  = SW_PVDDCR_CPU0_P1_PH3
  33  BOOT  POWER  = SW_PVDDCR_CPU0_P1_BOOT3
  34  PWM  IN  = PVDDCR_CPU0_P1_PWM3
  35  EN  IN  = PVDDCR_CPU0_P1_VCC3
  36  TOUT_FLT  OUT  = PVDDCR_CPU0_P1_TEMP0
  37  LSET  OUT  = PVDDCR_CPU0_P1_LSET3
  38  IOUT  OUT  = PVDDCR_CPU0_P1_IMON3
  39  REFIN  IN  = PVDDCR_CPU0_P1_VCCS
  40  PGND3  POWER  = GND
  41  GL2  OUT  = NC_PVDDCR_CPU0_P1_GL2_3
